FILE_TYPE = MACRO_DRAWING;
SET COLOR_WIRE YELLOW;
SET COLOR_PROP ORANGE;
SET COLOR_DOT WHITE;
SET COLOR_ARC YELLOW;
SET COLOR_BODY GREEN;
SET COLOR_NOTE PURPLE;
SET PROP_DISPLAY VALUE;
SET PAGE_NUMBER P128;
FORCEADD OFFPAGE..1
(-7300 3375);
FORCEPROP 2 LAST $XR0 13 
J 0
(-7521 3375);
DISPLAY 0.638298 (-7521 3375);
PAINT MONO (-7521 3375);
FORCEPROP 2 LAST CDS_LIB standard
J 0
(-7300 3375);
PAINT MONO (-7300 3375);
DISPLAY INVISIBLE (-7300 3375);
FORCEPROP 1 LAST OFFPAGE TRUE
J 0
(-6975 3250);
DISPLAY 0.872340 (-6975 3250);
PAINT GREEN (-6975 3250);
DISPLAY INVISIBLE (-6975 3250);
FORCEPROP 1 LAST COMMENT_BODY TRUE
J 0
(-7175 3275);
DISPLAY 0.872340 (-7175 3275);
PAINT GREEN (-7175 3275);
DISPLAY INVISIBLE (-7175 3275);
FORCEPROP 2 LAST PATH I1
J 0
(-7600 3425);
DISPLAY 1.021277 (-7600 3425);
DISPLAY INVISIBLE (-7600 3425);
FORCEADD Q_RES..1
(-5325 3325);
FORCEPROP 1 LAST PART_NUMBER CS00002JB13
J 0
(-5450 3175);
DISPLAY 0.510638 (-5450 3175);
DISPLAY INVISIBLE (-5450 3175);
FORCEPROP 1 LAST VALUE 0
J 2
(-5175 3325);
DISPLAY 0.638298 (-5175 3325);
FORCEPROP 1 LAST TOLERANCE 5%
J 0
(-5150 3325);
DISPLAY 0.638298 (-5150 3325);
FORCEPROP 1 LAST $LOCATION R853
J 0
(-5525 3325);
DISPLAY 0.638298 (-5525 3325);
FORCEPROP 1 LASTPIN (-5425 3325) $PN 1
J 0
(-5413 3337);
DISPLAY 0.787234 (-5413 3337);
FORCEPROP 1 LASTPIN (-5225 3325) $PN 2
J 0
(-5263 3337);
DISPLAY 0.787234 (-5263 3337);
FORCEPROP 1 LAST PACK_TYPE 0402LF
J 0
(-5075 3325);
DISPLAY 0.638298 (-5075 3325);
DISPLAY INVISIBLE (-5075 3325);
FORCEPROP 2 LAST CDS_LIB pure_quanta
J 0
(-5325 3325);
PAINT MONO (-5325 3325);
DISPLAY INVISIBLE (-5325 3325);
FORCEPROP 1 LAST MATERIAL CHIP
J 0
(-5325 3175);
DISPLAY 0.978723 (-5325 3175);
DISPLAY INVISIBLE (-5325 3175);
FORCEPROP 1 LAST WATTAGE 1/16W
J 2
(-5350 3175);
DISPLAY 0.978723 (-5350 3175);
DISPLAY INVISIBLE (-5350 3175);
FORCEPROP 1 LAST PATH I10
J 0
(-5375 3475);
DISPLAY 0.978723 (-5375 3475);
PAINT WHITE (-5375 3475);
DISPLAY INVISIBLE (-5375 3475);
FORCEPROP 1 LAST $LOCATION R853
J 0
(-5375 3525);
DISPLAY 1.021277 (-5375 3525);
DISPLAY INVISIBLE (-5375 3525);
FORCEPROP 2 LAST CDS_LOCATION R853
J 0
(-5375 3525);
DISPLAY 1.021277 (-5375 3525);
DISPLAY INVISIBLE (-5375 3525);
FORCEPROP 2 LAST $SEC 1
J 0
(-5375 3525);
DISPLAY 0.680851 (-5375 3525);
PAINT MONO (-5375 3525);
DISPLAY INVISIBLE (-5375 3525);
FORCEPROP 2 LAST CDS_SEC 1
J 0
(-5375 3525);
DISPLAY 1.021277 (-5375 3525);
DISPLAY INVISIBLE (-5375 3525);
FORCEADD Q_RES..1
(-5325 3375);
FORCEPROP 1 LAST PART_NUMBER CS00002JB13
J 0
(-5450 3225);
DISPLAY 0.510638 (-5450 3225);
DISPLAY INVISIBLE (-5450 3225);
FORCEPROP 1 LAST VALUE 0
J 2
(-5175 3375);
DISPLAY 0.638298 (-5175 3375);
FORCEPROP 1 LAST TOLERANCE 5%
J 0
(-5150 3375);
DISPLAY 0.638298 (-5150 3375);
FORCEPROP 1 LAST $LOCATION R852
J 0
(-5525 3375);
DISPLAY 0.638298 (-5525 3375);
FORCEPROP 1 LASTPIN (-5425 3375) $PN 1
J 0
(-5413 3387);
DISPLAY 0.787234 (-5413 3387);
FORCEPROP 1 LASTPIN (-5225 3375) $PN 2
J 0
(-5263 3387);
DISPLAY 0.787234 (-5263 3387);
FORCEPROP 1 LAST PACK_TYPE 0402LF
J 0
(-5075 3375);
DISPLAY 0.638298 (-5075 3375);
DISPLAY INVISIBLE (-5075 3375);
FORCEPROP 2 LAST CDS_LIB pure_quanta
J 0
(-5325 3375);
PAINT MONO (-5325 3375);
DISPLAY INVISIBLE (-5325 3375);
FORCEPROP 1 LAST MATERIAL CHIP
J 0
(-5325 3225);
DISPLAY 0.978723 (-5325 3225);
DISPLAY INVISIBLE (-5325 3225);
FORCEPROP 1 LAST WATTAGE 1/16W
J 2
(-5350 3225);
DISPLAY 0.978723 (-5350 3225);
DISPLAY INVISIBLE (-5350 3225);
FORCEPROP 1 LAST PATH I11
J 0
(-5375 3525);
DISPLAY 0.978723 (-5375 3525);
PAINT WHITE (-5375 3525);
DISPLAY INVISIBLE (-5375 3525);
FORCEPROP 1 LAST $LOCATION R852
J 0
(-5375 3575);
DISPLAY 1.021277 (-5375 3575);
DISPLAY INVISIBLE (-5375 3575);
FORCEPROP 2 LAST CDS_LOCATION R852
J 0
(-5375 3575);
DISPLAY 1.021277 (-5375 3575);
DISPLAY INVISIBLE (-5375 3575);
FORCEPROP 2 LAST $SEC 1
J 0
(-5375 3575);
DISPLAY 0.680851 (-5375 3575);
PAINT MONO (-5375 3575);
DISPLAY INVISIBLE (-5375 3575);
FORCEPROP 2 LAST CDS_SEC 1
J 0
(-5375 3575);
DISPLAY 1.021277 (-5375 3575);
DISPLAY INVISIBLE (-5375 3575);
FORCEADD Q_RES..1
(-5325 3425);
FORCEPROP 1 LAST PART_NUMBER CS00002JB13
J 0
(-5425 3500);
DISPLAY 0.510638 (-5425 3500);
DISPLAY INVISIBLE (-5425 3500);
FORCEPROP 1 LAST TOLERANCE 5%
J 0
(-5150 3425);
DISPLAY 0.638298 (-5150 3425);
FORCEPROP 1 LAST VALUE 0
J 2
(-5175 3425);
DISPLAY 0.638298 (-5175 3425);
FORCEPROP 1 LAST PACK_TYPE 0402LF
J 0
(-5175 3550);
DISPLAY 0.510638 (-5175 3550);
FORCEPROP 1 LAST WATTAGE 1/16W
J 2
(-5200 3550);
DISPLAY 0.510638 (-5200 3550);
FORCEPROP 1 LAST MATERIAL CHIP
J 0
(-5425 3550);
DISPLAY 0.510638 (-5425 3550);
FORCEPROP 1 LAST $LOCATION R851
J 0
(-5525 3425);
DISPLAY 0.638298 (-5525 3425);
FORCEPROP 1 LASTPIN (-5425 3425) $PN 1
J 0
(-5413 3437);
DISPLAY 0.787234 (-5413 3437);
FORCEPROP 1 LASTPIN (-5225 3425) $PN 2
J 0
(-5263 3437);
DISPLAY 0.787234 (-5263 3437);
FORCEPROP 2 LAST CDS_LIB pure_quanta
J 0
(-5325 3425);
PAINT MONO (-5325 3425);
DISPLAY INVISIBLE (-5325 3425);
FORCEPROP 1 LAST PATH I12
J 0
(-5375 3575);
DISPLAY 0.978723 (-5375 3575);
PAINT WHITE (-5375 3575);
DISPLAY INVISIBLE (-5375 3575);
FORCEPROP 1 LAST $LOCATION R851
J 0
(-5375 3625);
DISPLAY 1.021277 (-5375 3625);
DISPLAY INVISIBLE (-5375 3625);
FORCEPROP 2 LAST CDS_LOCATION R851
J 0
(-5375 3625);
DISPLAY 1.021277 (-5375 3625);
DISPLAY INVISIBLE (-5375 3625);
FORCEPROP 2 LAST $SEC 1
J 0
(-5375 3625);
DISPLAY 0.680851 (-5375 3625);
PAINT MONO (-5375 3625);
DISPLAY INVISIBLE (-5375 3625);
FORCEPROP 2 LAST CDS_SEC 1
J 0
(-5375 3625);
DISPLAY 1.021277 (-5375 3625);
DISPLAY INVISIBLE (-5375 3625);
FORCEADD OFFPAGE..1
(-7300 3325);
FORCEPROP 2 LAST $XR0 13 
J 0
(-7521 3325);
DISPLAY 0.638298 (-7521 3325);
PAINT MONO (-7521 3325);
FORCEPROP 2 LAST CDS_LIB standard
J 0
(-7300 3325);
PAINT MONO (-7300 3325);
DISPLAY INVISIBLE (-7300 3325);
FORCEPROP 1 LAST OFFPAGE TRUE
J 0
(-6975 3200);
DISPLAY 0.872340 (-6975 3200);
PAINT GREEN (-6975 3200);
DISPLAY INVISIBLE (-6975 3200);
FORCEPROP 1 LAST COMMENT_BODY TRUE
J 0
(-7175 3225);
DISPLAY 0.872340 (-7175 3225);
PAINT GREEN (-7175 3225);
DISPLAY INVISIBLE (-7175 3225);
FORCEPROP 2 LAST PATH I2
J 0
(-7250 3400);
DISPLAY 1.021277 (-7250 3400);
DISPLAY INVISIBLE (-7250 3400);
FORCEADD OFFPAGE..1
(-7300 3275);
FORCEPROP 2 LAST $XR0 13 
J 0
(-7521 3275);
DISPLAY 0.638298 (-7521 3275);
PAINT MONO (-7521 3275);
FORCEPROP 2 LAST CDS_LIB standard
J 0
(-7300 3275);
PAINT MONO (-7300 3275);
DISPLAY INVISIBLE (-7300 3275);
FORCEPROP 1 LAST OFFPAGE TRUE
J 0
(-6975 3150);
DISPLAY 0.872340 (-6975 3150);
PAINT GREEN (-6975 3150);
DISPLAY INVISIBLE (-6975 3150);
FORCEPROP 1 LAST COMMENT_BODY TRUE
J 0
(-7175 3175);
DISPLAY 0.872340 (-7175 3175);
PAINT GREEN (-7175 3175);
DISPLAY INVISIBLE (-7175 3175);
FORCEPROP 2 LAST PATH I3
J 0
(-7250 3350);
DISPLAY 1.021277 (-7250 3350);
DISPLAY INVISIBLE (-7250 3350);
FORCEADD OFFPAGE..2
(-850 3375);
FORCEPROP 2 LAST $XR0 225 
J 0
(-661 3375);
DISPLAY 0.638298 (-661 3375);
PAINT MONO (-661 3375);
FORCEPROP 2 LAST CDS_LIB standard
J 0
(-850 3375);
DISPLAY INVISIBLE (-850 3375);
FORCEPROP 1 LAST OFFPAGE TRUE
J 0
(-525 3250);
DISPLAY 0.872340 (-525 3250);
PAINT GREEN (-525 3250);
DISPLAY INVISIBLE (-525 3250);
FORCEPROP 1 LAST COMMENT_BODY TRUE
J 0
(-895 3280);
DISPLAY 0.872340 (-895 3280);
PAINT GREEN (-895 3280);
DISPLAY INVISIBLE (-895 3280);
FORCEPROP 2 LAST PATH I30
J 0
(-650 3425);
DISPLAY 1.021277 (-650 3425);
DISPLAY INVISIBLE (-650 3425);
FORCEADD OFFPAGE..2
(-850 3275);
FORCEPROP 2 LAST $XR0 225 
J 0
(-661 3275);
DISPLAY 0.638298 (-661 3275);
PAINT MONO (-661 3275);
FORCEPROP 2 LAST CDS_LIB standard
J 0
(-850 3275);
PAINT MONO (-850 3275);
DISPLAY INVISIBLE (-850 3275);
FORCEPROP 1 LAST OFFPAGE TRUE
J 0
(-525 3150);
DISPLAY 0.872340 (-525 3150);
PAINT GREEN (-525 3150);
DISPLAY INVISIBLE (-525 3150);
FORCEPROP 1 LAST COMMENT_BODY TRUE
J 0
(-895 3180);
DISPLAY 0.872340 (-895 3180);
PAINT GREEN (-895 3180);
DISPLAY INVISIBLE (-895 3180);
FORCEPROP 2 LAST PATH I31
J 0
(-650 3325);
DISPLAY 1.021277 (-650 3325);
DISPLAY INVISIBLE (-650 3325);
FORCEADD OFFPAGE..2
(-850 3325);
FORCEPROP 2 LAST $XR0 225 
J 0
(-661 3325);
DISPLAY 0.638298 (-661 3325);
PAINT MONO (-661 3325);
FORCEPROP 2 LAST CDS_LIB standard
J 0
(-850 3325);
PAINT MONO (-850 3325);
DISPLAY INVISIBLE (-850 3325);
FORCEPROP 1 LAST OFFPAGE TRUE
J 0
(-525 3200);
DISPLAY 0.872340 (-525 3200);
PAINT GREEN (-525 3200);
DISPLAY INVISIBLE (-525 3200);
FORCEPROP 1 LAST COMMENT_BODY TRUE
J 0
(-895 3230);
DISPLAY 0.872340 (-895 3230);
PAINT GREEN (-895 3230);
DISPLAY INVISIBLE (-895 3230);
FORCEPROP 2 LAST PATH I32
J 0
(-650 3375);
DISPLAY 1.021277 (-650 3375);
DISPLAY INVISIBLE (-650 3375);
FORCEADD OFFPAGE..2
(-850 3425);
FORCEPROP 2 LAST $XR0 225 
J 0
(-661 3425);
DISPLAY 0.638298 (-661 3425);
PAINT MONO (-661 3425);
FORCEPROP 2 LAST CDS_LIB standard
J 0
(-850 3425);
DISPLAY INVISIBLE (-850 3425);
FORCEPROP 1 LAST OFFPAGE TRUE
J 0
(-525 3300);
DISPLAY 0.872340 (-525 3300);
PAINT GREEN (-525 3300);
DISPLAY INVISIBLE (-525 3300);
FORCEPROP 1 LAST COMMENT_BODY TRUE
J 0
(-895 3330);
DISPLAY 0.872340 (-895 3330);
PAINT GREEN (-895 3330);
DISPLAY INVISIBLE (-895 3330);
FORCEPROP 2 LAST PATH I33
J 0
(-650 3475);
DISPLAY 1.021277 (-650 3475);
DISPLAY INVISIBLE (-650 3475);
FORCEADD OFFPAGE..1
(-7300 3425);
FORCEPROP 2 LAST $XR0 13 
J 0
(-7521 3425);
DISPLAY 0.638298 (-7521 3425);
PAINT MONO (-7521 3425);
FORCEPROP 2 LAST CDS_LIB standard
J 0
(-7300 3425);
PAINT MONO (-7300 3425);
DISPLAY INVISIBLE (-7300 3425);
FORCEPROP 1 LAST OFFPAGE TRUE
J 0
(-6975 3300);
DISPLAY 0.872340 (-6975 3300);
PAINT GREEN (-6975 3300);
DISPLAY INVISIBLE (-6975 3300);
FORCEPROP 1 LAST COMMENT_BODY TRUE
J 0
(-7175 3325);
DISPLAY 0.872340 (-7175 3325);
PAINT GREEN (-7175 3325);
DISPLAY INVISIBLE (-7175 3325);
FORCEPROP 2 LAST PATH I4
J 0
(-7600 3475);
DISPLAY 1.021277 (-7600 3475);
DISPLAY INVISIBLE (-7600 3475);
FORCEADD OFFPAGE..1
(-7300 375);
FORCEPROP 2 LAST $XR0 44 
J 0
(-7521 375);
DISPLAY 0.638298 (-7521 375);
PAINT MONO (-7521 375);
FORCEPROP 2 LAST CDS_LIB standard
J 0
(-7300 375);
PAINT MONO (-7300 375);
DISPLAY INVISIBLE (-7300 375);
FORCEPROP 1 LAST OFFPAGE TRUE
J 0
(-6975 250);
DISPLAY 0.872340 (-6975 250);
PAINT GREEN (-6975 250);
DISPLAY INVISIBLE (-6975 250);
FORCEPROP 1 LAST COMMENT_BODY TRUE
J 0
(-7175 275);
DISPLAY 0.872340 (-7175 275);
PAINT GREEN (-7175 275);
DISPLAY INVISIBLE (-7175 275);
FORCEPROP 2 LAST PATH I44
J 0
(-7250 450);
DISPLAY 1.021277 (-7250 450);
DISPLAY INVISIBLE (-7250 450);
FORCEADD OFFPAGE..1
(-7300 425);
FORCEPROP 2 LAST $XR0 44 
J 0
(-7521 425);
DISPLAY 0.638298 (-7521 425);
PAINT MONO (-7521 425);
FORCEPROP 2 LAST CDS_LIB standard
J 0
(-7300 425);
PAINT MONO (-7300 425);
DISPLAY INVISIBLE (-7300 425);
FORCEPROP 1 LAST OFFPAGE TRUE
J 0
(-6975 300);
DISPLAY 0.872340 (-6975 300);
PAINT GREEN (-6975 300);
DISPLAY INVISIBLE (-6975 300);
FORCEPROP 1 LAST COMMENT_BODY TRUE
J 0
(-7175 325);
DISPLAY 0.872340 (-7175 325);
PAINT GREEN (-7175 325);
DISPLAY INVISIBLE (-7175 325);
FORCEPROP 2 LAST PATH I45
J 0
(-7250 500);
DISPLAY 1.021277 (-7250 500);
DISPLAY INVISIBLE (-7250 500);
FORCEADD OFFPAGE..1
(-7300 525);
FORCEPROP 2 LAST $XR0 44 
J 0
(-7521 525);
DISPLAY 0.638298 (-7521 525);
PAINT MONO (-7521 525);
FORCEPROP 2 LAST CDS_LIB standard
J 0
(-7300 525);
PAINT MONO (-7300 525);
DISPLAY INVISIBLE (-7300 525);
FORCEPROP 1 LAST OFFPAGE TRUE
J 0
(-6975 400);
DISPLAY 0.872340 (-6975 400);
PAINT GREEN (-6975 400);
DISPLAY INVISIBLE (-6975 400);
FORCEPROP 1 LAST COMMENT_BODY TRUE
J 0
(-7175 425);
DISPLAY 0.872340 (-7175 425);
PAINT GREEN (-7175 425);
DISPLAY INVISIBLE (-7175 425);
FORCEPROP 2 LAST PATH I46
J 0
(-7600 575);
DISPLAY 1.021277 (-7600 575);
DISPLAY INVISIBLE (-7600 575);
FORCEADD OFFPAGE..1
(-7300 475);
FORCEPROP 2 LAST $XR0 44 
J 0
(-7521 475);
DISPLAY 0.638298 (-7521 475);
PAINT MONO (-7521 475);
FORCEPROP 2 LAST CDS_LIB standard
J 0
(-7300 475);
PAINT MONO (-7300 475);
DISPLAY INVISIBLE (-7300 475);
FORCEPROP 1 LAST OFFPAGE TRUE
J 0
(-6975 350);
DISPLAY 0.872340 (-6975 350);
PAINT GREEN (-6975 350);
DISPLAY INVISIBLE (-6975 350);
FORCEPROP 1 LAST COMMENT_BODY TRUE
J 0
(-7175 375);
DISPLAY 0.872340 (-7175 375);
PAINT GREEN (-7175 375);
DISPLAY INVISIBLE (-7175 375);
FORCEPROP 2 LAST PATH I47
J 0
(-7600 525);
DISPLAY 1.021277 (-7600 525);
DISPLAY INVISIBLE (-7600 525);
FORCEADD Q_RES..1
(-5325 425);
FORCEPROP 1 LAST PART_NUMBER CS00002JB13
J 0
(-5450 275);
DISPLAY 0.510638 (-5450 275);
DISPLAY INVISIBLE (-5450 275);
FORCEPROP 1 LAST TOLERANCE 5%
J 0
(-5150 425);
DISPLAY 0.638298 (-5150 425);
FORCEPROP 1 LAST VALUE 0
J 2
(-5175 425);
DISPLAY 0.638298 (-5175 425);
FORCEPROP 1 LAST $LOCATION R861
J 0
(-5525 425);
DISPLAY 0.638298 (-5525 425);
FORCEPROP 1 LASTPIN (-5425 425) $PN 1
J 0
(-5413 437);
DISPLAY 0.787234 (-5413 437);
FORCEPROP 1 LASTPIN (-5225 425) $PN 2
J 0
(-5263 437);
DISPLAY 0.787234 (-5263 437);
FORCEPROP 1 LAST PACK_TYPE 0402LF
J 0
(-5075 425);
DISPLAY 0.638298 (-5075 425);
DISPLAY INVISIBLE (-5075 425);
FORCEPROP 2 LAST CDS_LIB pure_quanta
J 0
(-5325 425);
PAINT MONO (-5325 425);
DISPLAY INVISIBLE (-5325 425);
FORCEPROP 1 LAST MATERIAL CHIP
J 0
(-5325 275);
DISPLAY 0.978723 (-5325 275);
DISPLAY INVISIBLE (-5325 275);
FORCEPROP 1 LAST WATTAGE 1/16W
J 2
(-5350 275);
DISPLAY 0.978723 (-5350 275);
DISPLAY INVISIBLE (-5350 275);
FORCEPROP 1 LAST PATH I48
J 0
(-5375 575);
DISPLAY 0.978723 (-5375 575);
PAINT WHITE (-5375 575);
DISPLAY INVISIBLE (-5375 575);
FORCEPROP 1 LAST $LOCATION R861
J 0
(-5375 625);
DISPLAY 1.021277 (-5375 625);
DISPLAY INVISIBLE (-5375 625);
FORCEPROP 2 LAST CDS_LOCATION R861
J 0
(-5375 625);
DISPLAY 1.021277 (-5375 625);
DISPLAY INVISIBLE (-5375 625);
FORCEPROP 2 LAST $SEC 1
J 0
(-5375 625);
DISPLAY 0.680851 (-5375 625);
PAINT MONO (-5375 625);
DISPLAY INVISIBLE (-5375 625);
FORCEPROP 2 LAST CDS_SEC 1
J 0
(-5375 625);
DISPLAY 1.021277 (-5375 625);
DISPLAY INVISIBLE (-5375 625);
FORCEADD Q_RES..1
(-5325 375);
FORCEPROP 1 LAST PART_NUMBER CS00002JB13
J 0
(-5450 225);
DISPLAY 0.510638 (-5450 225);
DISPLAY INVISIBLE (-5450 225);
FORCEPROP 1 LAST TOLERANCE 5%
J 0
(-5150 375);
DISPLAY 0.638298 (-5150 375);
FORCEPROP 1 LAST VALUE 0
J 2
(-5175 375);
DISPLAY 0.638298 (-5175 375);
FORCEPROP 1 LAST $LOCATION R2969
J 0
(-5525 375);
DISPLAY 0.638298 (-5525 375);
FORCEPROP 1 LASTPIN (-5425 375) $PN 1
J 0
(-5413 387);
DISPLAY 0.787234 (-5413 387);
FORCEPROP 1 LASTPIN (-5225 375) $PN 2
J 0
(-5263 387);
DISPLAY 0.787234 (-5263 387);
FORCEPROP 1 LAST WATTAGE 1/16W
J 2
(-5350 225);
DISPLAY 0.978723 (-5350 225);
DISPLAY INVISIBLE (-5350 225);
FORCEPROP 1 LAST MATERIAL CHIP
J 0
(-5325 225);
DISPLAY 0.978723 (-5325 225);
DISPLAY INVISIBLE (-5325 225);
FORCEPROP 2 LAST CDS_LIB pure_quanta
J 0
(-5325 375);
PAINT MONO (-5325 375);
DISPLAY INVISIBLE (-5325 375);
FORCEPROP 1 LAST PACK_TYPE 0402LF
J 0
(-5075 375);
DISPLAY 0.638298 (-5075 375);
DISPLAY INVISIBLE (-5075 375);
FORCEPROP 1 LAST PATH I49
J 0
(-5375 525);
DISPLAY 0.978723 (-5375 525);
PAINT WHITE (-5375 525);
DISPLAY INVISIBLE (-5375 525);
FORCEPROP 2 LAST CDS_LOCATION R2969
J 0
(-5375 575);
DISPLAY 1.021277 (-5375 575);
DISPLAY INVISIBLE (-5375 575);
FORCEPROP 2 LAST $SEC 1
J 0
(-5375 575);
DISPLAY 0.680851 (-5375 575);
PAINT MONO (-5375 575);
DISPLAY INVISIBLE (-5375 575);
FORCEPROP 2 LAST CDS_SEC 1
J 0
(-5375 575);
DISPLAY 1.021277 (-5375 575);
DISPLAY INVISIBLE (-5375 575);
FORCEADD Q_RES..1
(-5325 525);
FORCEPROP 1 LAST PART_NUMBER CS00002JB13
J 0
(-5425 600);
DISPLAY 0.510638 (-5425 600);
DISPLAY INVISIBLE (-5425 600);
FORCEPROP 1 LAST MATERIAL CHIP
J 0
(-5425 650);
DISPLAY 0.510638 (-5425 650);
FORCEPROP 1 LAST PACK_TYPE 0402LF
J 0
(-5175 650);
DISPLAY 0.510638 (-5175 650);
FORCEPROP 1 LAST VALUE 0
J 2
(-5175 525);
DISPLAY 0.638298 (-5175 525);
FORCEPROP 1 LAST TOLERANCE 5%
J 0
(-5150 525);
DISPLAY 0.638298 (-5150 525);
FORCEPROP 1 LAST WATTAGE 1/16W
J 2
(-5200 650);
DISPLAY 0.510638 (-5200 650);
FORCEPROP 1 LAST $LOCATION R859
J 0
(-5525 525);
DISPLAY 0.638298 (-5525 525);
FORCEPROP 1 LASTPIN (-5425 525) $PN 1
J 0
(-5413 537);
DISPLAY 0.787234 (-5413 537);
FORCEPROP 1 LASTPIN (-5225 525) $PN 2
J 0
(-5263 537);
DISPLAY 0.787234 (-5263 537);
FORCEPROP 2 LAST CDS_LIB pure_quanta
J 0
(-5325 525);
PAINT MONO (-5325 525);
DISPLAY INVISIBLE (-5325 525);
FORCEPROP 1 LAST PATH I50
J 0
(-5375 675);
DISPLAY 0.978723 (-5375 675);
PAINT WHITE (-5375 675);
DISPLAY INVISIBLE (-5375 675);
FORCEPROP 1 LAST $LOCATION R859
J 0
(-5375 725);
DISPLAY 1.021277 (-5375 725);
DISPLAY INVISIBLE (-5375 725);
FORCEPROP 2 LAST CDS_LOCATION R859
J 0
(-5375 725);
DISPLAY 1.021277 (-5375 725);
DISPLAY INVISIBLE (-5375 725);
FORCEPROP 2 LAST $SEC 1
J 0
(-5375 725);
DISPLAY 0.680851 (-5375 725);
PAINT MONO (-5375 725);
DISPLAY INVISIBLE (-5375 725);
FORCEPROP 2 LAST CDS_SEC 1
J 0
(-5375 725);
DISPLAY 1.021277 (-5375 725);
DISPLAY INVISIBLE (-5375 725);
FORCEADD Q_RES..1
(-5325 475);
FORCEPROP 1 LAST PART_NUMBER CS00002JB13
J 0
(-5450 325);
DISPLAY 0.510638 (-5450 325);
DISPLAY INVISIBLE (-5450 325);
FORCEPROP 1 LAST TOLERANCE 5%
J 0
(-5150 475);
DISPLAY 0.638298 (-5150 475);
FORCEPROP 1 LAST VALUE 0
J 2
(-5175 475);
DISPLAY 0.638298 (-5175 475);
FORCEPROP 1 LAST $LOCATION R860
J 0
(-5525 475);
DISPLAY 0.638298 (-5525 475);
FORCEPROP 1 LASTPIN (-5425 475) $PN 1
J 0
(-5413 487);
DISPLAY 0.787234 (-5413 487);
FORCEPROP 1 LASTPIN (-5225 475) $PN 2
J 0
(-5263 487);
DISPLAY 0.787234 (-5263 487);
FORCEPROP 1 LAST PACK_TYPE 0402LF
J 0
(-5075 475);
DISPLAY 0.638298 (-5075 475);
DISPLAY INVISIBLE (-5075 475);
FORCEPROP 2 LAST CDS_LIB pure_quanta
J 0
(-5325 475);
PAINT MONO (-5325 475);
DISPLAY INVISIBLE (-5325 475);
FORCEPROP 1 LAST MATERIAL CHIP
J 0
(-5325 325);
DISPLAY 0.978723 (-5325 325);
DISPLAY INVISIBLE (-5325 325);
FORCEPROP 1 LAST WATTAGE 1/16W
J 2
(-5350 325);
DISPLAY 0.978723 (-5350 325);
DISPLAY INVISIBLE (-5350 325);
FORCEPROP 1 LAST PATH I51
J 0
(-5375 625);
DISPLAY 0.978723 (-5375 625);
PAINT WHITE (-5375 625);
DISPLAY INVISIBLE (-5375 625);
FORCEPROP 1 LAST $LOCATION R860
J 0
(-5375 675);
DISPLAY 1.021277 (-5375 675);
DISPLAY INVISIBLE (-5375 675);
FORCEPROP 2 LAST CDS_LOCATION R860
J 0
(-5375 675);
DISPLAY 1.021277 (-5375 675);
DISPLAY INVISIBLE (-5375 675);
FORCEPROP 2 LAST $SEC 1
J 0
(-5375 675);
DISPLAY 0.680851 (-5375 675);
PAINT MONO (-5375 675);
DISPLAY INVISIBLE (-5375 675);
FORCEPROP 2 LAST CDS_SEC 1
J 0
(-5375 675);
DISPLAY 1.021277 (-5375 675);
DISPLAY INVISIBLE (-5375 675);
FORCEADD OFFPAGE..2
(-850 425);
FORCEPROP 2 LAST $XR0 225 
J 0
(-661 425);
DISPLAY 0.638298 (-661 425);
PAINT MONO (-661 425);
FORCEPROP 2 LAST CDS_LIB standard
J 0
(-850 425);
PAINT MONO (-850 425);
DISPLAY INVISIBLE (-850 425);
FORCEPROP 1 LAST OFFPAGE TRUE
J 0
(-525 300);
DISPLAY 0.872340 (-525 300);
PAINT GREEN (-525 300);
DISPLAY INVISIBLE (-525 300);
FORCEPROP 1 LAST COMMENT_BODY TRUE
J 0
(-895 330);
DISPLAY 0.872340 (-895 330);
PAINT GREEN (-895 330);
DISPLAY INVISIBLE (-895 330);
FORCEPROP 2 LAST PATH I68
J 0
(-650 475);
DISPLAY 1.021277 (-650 475);
DISPLAY INVISIBLE (-650 475);
FORCEADD OFFPAGE..2
(-850 375);
FORCEPROP 2 LAST $XR0 225 
J 0
(-661 375);
DISPLAY 0.638298 (-661 375);
PAINT MONO (-661 375);
FORCEPROP 2 LAST CDS_LIB standard
J 0
(-850 375);
PAINT MONO (-850 375);
DISPLAY INVISIBLE (-850 375);
FORCEPROP 1 LAST OFFPAGE TRUE
J 0
(-525 250);
DISPLAY 0.872340 (-525 250);
PAINT GREEN (-525 250);
DISPLAY INVISIBLE (-525 250);
FORCEPROP 1 LAST COMMENT_BODY TRUE
J 0
(-895 280);
DISPLAY 0.872340 (-895 280);
PAINT GREEN (-895 280);
DISPLAY INVISIBLE (-895 280);
FORCEPROP 2 LAST PATH I69
J 0
(-650 425);
DISPLAY 1.021277 (-650 425);
DISPLAY INVISIBLE (-650 425);
FORCEADD OFFPAGE..2
(-850 525);
FORCEPROP 2 LAST $XR0 225 
J 0
(-661 525);
DISPLAY 0.638298 (-661 525);
PAINT MONO (-661 525);
FORCEPROP 2 LAST CDS_LIB standard
J 0
(-850 525);
DISPLAY INVISIBLE (-850 525);
FORCEPROP 1 LAST OFFPAGE TRUE
J 0
(-525 400);
DISPLAY 0.872340 (-525 400);
PAINT GREEN (-525 400);
DISPLAY INVISIBLE (-525 400);
FORCEPROP 1 LAST COMMENT_BODY TRUE
J 0
(-895 430);
DISPLAY 0.872340 (-895 430);
PAINT GREEN (-895 430);
DISPLAY INVISIBLE (-895 430);
FORCEPROP 2 LAST PATH I70
J 0
(-650 575);
DISPLAY 1.021277 (-650 575);
DISPLAY INVISIBLE (-650 575);
FORCEADD OFFPAGE..2
(-850 475);
FORCEPROP 2 LAST $XR0 225 
J 0
(-661 475);
DISPLAY 0.638298 (-661 475);
PAINT MONO (-661 475);
FORCEPROP 2 LAST CDS_LIB standard
J 0
(-850 475);
DISPLAY INVISIBLE (-850 475);
FORCEPROP 1 LAST OFFPAGE TRUE
J 0
(-525 350);
DISPLAY 0.872340 (-525 350);
PAINT GREEN (-525 350);
DISPLAY INVISIBLE (-525 350);
FORCEPROP 1 LAST COMMENT_BODY TRUE
J 0
(-895 380);
DISPLAY 0.872340 (-895 380);
PAINT GREEN (-895 380);
DISPLAY INVISIBLE (-895 380);
FORCEPROP 2 LAST PATH I71
J 0
(-650 525);
DISPLAY 1.021277 (-650 525);
DISPLAY INVISIBLE (-650 525);
FORCEADD Q_RES..2
(-6500 3000);
FORCEPROP 1 LAST PART_NUMBER CS31002FB08
J 0
(-6460 2825);
DISPLAY 0.510638 (-6460 2825);
DISPLAY INVISIBLE (-6460 2825);
FORCEPROP 1 LAST VALUE 10K
J 0
(-6455 3075);
DISPLAY 0.510638 (-6455 3075);
FORCEPROP 1 LAST MATERIAL CHIP
J 0
(-6460 2925);
DISPLAY 0.510638 (-6460 2925);
FORCEPROP 1 LAST TOLERANCE 1%
J 0
(-6455 3025);
DISPLAY 0.510638 (-6455 3025);
FORCEPROP 1 LAST WATTAGE 1/16W
J 0
(-6460 2975);
DISPLAY 0.510638 (-6460 2975);
FORCEPROP 1 LAST PACK_TYPE 0402LF
J 0
(-6460 2875);
DISPLAY 0.510638 (-6460 2875);
FORCEPROP 1 LAST $LOCATION R938
J 0
(-6455 3125);
DISPLAY 0.978723 (-6455 3125);
FORCEPROP 1 LASTPIN (-6500 3100) $PN 1
J 0
(-6495 3062);
DISPLAY 0.787234 (-6495 3062);
FORCEPROP 1 LASTPIN (-6500 2900) $PN 2
J 0
(-6495 2910);
DISPLAY 0.787234 (-6495 2910);
FORCEPROP 2 LAST CDS_LIB pure_quanta
J 0
(-6500 3000);
PAINT MONO (-6500 3000);
DISPLAY INVISIBLE (-6500 3000);
FORCEPROP 1 LAST PATH I77
J 0
(-6450 3175);
DISPLAY 0.978723 (-6450 3175);
PAINT WHITE (-6450 3175);
DISPLAY INVISIBLE (-6450 3175);
FORCEPROP 2 LAST CDS_LOCATION R938
J 0
(-6450 3225);
DISPLAY 1.021277 (-6450 3225);
DISPLAY INVISIBLE (-6450 3225);
FORCEPROP 2 LAST $SEC 1
J 0
(-6450 3225);
DISPLAY 0.680851 (-6450 3225);
PAINT MONO (-6450 3225);
DISPLAY INVISIBLE (-6450 3225);
FORCEPROP 2 LAST CDS_SEC 1
J 0
(-6450 3225);
DISPLAY 1.021277 (-6450 3225);
DISPLAY INVISIBLE (-6450 3225);
FORCEADD Q_RES..2
(-6700 3000);
FORCEPROP 1 LAST PART_NUMBER CS31002FB08
J 0
(-6660 2825);
DISPLAY 0.510638 (-6660 2825);
DISPLAY INVISIBLE (-6660 2825);
FORCEPROP 1 LAST VALUE 10K
J 0
(-6655 3075);
DISPLAY 0.510638 (-6655 3075);
FORCEPROP 1 LAST PACK_TYPE 0402LF
J 0
(-6660 2875);
DISPLAY 0.510638 (-6660 2875);
FORCEPROP 1 LAST WATTAGE 1/16W
J 0
(-6660 2975);
DISPLAY 0.510638 (-6660 2975);
FORCEPROP 1 LAST TOLERANCE 1%
J 0
(-6655 3025);
DISPLAY 0.510638 (-6655 3025);
FORCEPROP 1 LAST MATERIAL CHIP
J 0
(-6660 2925);
DISPLAY 0.510638 (-6660 2925);
FORCEPROP 1 LAST $LOCATION R936
J 0
(-6655 3125);
DISPLAY 0.978723 (-6655 3125);
FORCEPROP 1 LASTPIN (-6700 3100) $PN 1
J 0
(-6695 3062);
DISPLAY 0.787234 (-6695 3062);
FORCEPROP 1 LASTPIN (-6700 2900) $PN 2
J 0
(-6695 2910);
DISPLAY 0.787234 (-6695 2910);
FORCEPROP 2 LAST CDS_LIB pure_quanta
J 0
(-6700 3000);
PAINT MONO (-6700 3000);
DISPLAY INVISIBLE (-6700 3000);
FORCEPROP 1 LAST PATH I78
J 0
(-6650 3175);
DISPLAY 0.978723 (-6650 3175);
PAINT WHITE (-6650 3175);
DISPLAY INVISIBLE (-6650 3175);
FORCEPROP 2 LAST CDS_LOCATION R936
J 0
(-6650 3225);
DISPLAY 1.021277 (-6650 3225);
DISPLAY INVISIBLE (-6650 3225);
FORCEPROP 2 LAST $SEC 1
J 0
(-6650 3225);
DISPLAY 0.680851 (-6650 3225);
PAINT MONO (-6650 3225);
DISPLAY INVISIBLE (-6650 3225);
FORCEPROP 2 LAST CDS_SEC 1
J 0
(-6650 3225);
DISPLAY 1.021277 (-6650 3225);
DISPLAY INVISIBLE (-6650 3225);
FORCEADD Q_RES..2
(-6900 3000);
FORCEPROP 1 LAST PART_NUMBER CS31002FB08
J 0
(-6860 2825);
DISPLAY 0.510638 (-6860 2825);
DISPLAY INVISIBLE (-6860 2825);
FORCEPROP 1 LAST VALUE 10K
J 0
(-6855 3075);
DISPLAY 0.510638 (-6855 3075);
FORCEPROP 1 LAST PACK_TYPE 0402LF
J 0
(-6860 2875);
DISPLAY 0.510638 (-6860 2875);
FORCEPROP 1 LAST WATTAGE 1/16W
J 0
(-6860 2975);
DISPLAY 0.510638 (-6860 2975);
FORCEPROP 1 LAST TOLERANCE 1%
J 0
(-6855 3025);
DISPLAY 0.510638 (-6855 3025);
FORCEPROP 1 LAST MATERIAL CHIP
J 0
(-6860 2925);
DISPLAY 0.510638 (-6860 2925);
FORCEPROP 1 LAST $LOCATION R934
J 0
(-6855 3125);
DISPLAY 0.978723 (-6855 3125);
FORCEPROP 1 LASTPIN (-6900 3100) $PN 1
J 0
(-6895 3062);
DISPLAY 0.787234 (-6895 3062);
FORCEPROP 1 LASTPIN (-6900 2900) $PN 2
J 0
(-6895 2910);
DISPLAY 0.787234 (-6895 2910);
FORCEPROP 2 LAST CDS_LIB pure_quanta
J 0
(-6900 3000);
PAINT MONO (-6900 3000);
DISPLAY INVISIBLE (-6900 3000);
FORCEPROP 1 LAST PATH I79
J 0
(-6850 3175);
DISPLAY 0.978723 (-6850 3175);
PAINT WHITE (-6850 3175);
DISPLAY INVISIBLE (-6850 3175);
FORCEPROP 2 LAST CDS_LOCATION R934
J 0
(-6850 3225);
DISPLAY 1.021277 (-6850 3225);
DISPLAY INVISIBLE (-6850 3225);
FORCEPROP 2 LAST $SEC 1
J 0
(-6850 3225);
DISPLAY 0.680851 (-6850 3225);
PAINT MONO (-6850 3225);
DISPLAY INVISIBLE (-6850 3225);
FORCEPROP 2 LAST CDS_SEC 1
J 0
(-6850 3225);
DISPLAY 1.021277 (-6850 3225);
DISPLAY INVISIBLE (-6850 3225);
FORCEADD Q_RES..2
(-7100 3000);
FORCEPROP 1 LAST PART_NUMBER CS31002FB08
J 0
(-7060 2825);
DISPLAY 0.510638 (-7060 2825);
DISPLAY INVISIBLE (-7060 2825);
FORCEPROP 1 LAST VALUE 10K
J 0
(-7055 3075);
DISPLAY 0.510638 (-7055 3075);
FORCEPROP 1 LAST MATERIAL CHIP
J 0
(-7060 2925);
DISPLAY 0.510638 (-7060 2925);
FORCEPROP 1 LAST TOLERANCE 1%
J 0
(-7055 3025);
DISPLAY 0.510638 (-7055 3025);
FORCEPROP 1 LAST WATTAGE 1/16W
J 0
(-7060 2975);
DISPLAY 0.510638 (-7060 2975);
FORCEPROP 1 LAST PACK_TYPE 0402LF
J 0
(-7060 2875);
DISPLAY 0.510638 (-7060 2875);
FORCEPROP 1 LAST $LOCATION R932
J 0
(-7055 3125);
DISPLAY 0.978723 (-7055 3125);
FORCEPROP 1 LASTPIN (-7100 3100) $PN 1
J 0
(-7095 3062);
DISPLAY 0.787234 (-7095 3062);
FORCEPROP 1 LASTPIN (-7100 2900) $PN 2
J 0
(-7095 2910);
DISPLAY 0.787234 (-7095 2910);
FORCEPROP 2 LAST CDS_LIB pure_quanta
J 0
(-7100 3000);
PAINT MONO (-7100 3000);
DISPLAY INVISIBLE (-7100 3000);
FORCEPROP 1 LAST PATH I80
J 0
(-7050 3175);
DISPLAY 0.978723 (-7050 3175);
PAINT WHITE (-7050 3175);
DISPLAY INVISIBLE (-7050 3175);
FORCEPROP 2 LAST CDS_LOCATION R932
J 0
(-7050 3225);
DISPLAY 1.021277 (-7050 3225);
DISPLAY INVISIBLE (-7050 3225);
FORCEPROP 2 LAST $SEC 1
J 0
(-7050 3225);
DISPLAY 0.680851 (-7050 3225);
PAINT MONO (-7050 3225);
DISPLAY INVISIBLE (-7050 3225);
FORCEPROP 2 LAST CDS_SEC 1
J 0
(-7050 3225);
DISPLAY 1.021277 (-7050 3225);
DISPLAY INVISIBLE (-7050 3225);
FORCEADD UNIVERSAL_GND..1
(-6500 2675);
FORCEPROP 3 LASTPIN (-6500 2725) SIG_NAME GND\g
J 0
(-6490 2735);
DISPLAY 0.659574 (-6490 2735);
PAINT MONO (-6490 2735);
DISPLAY INVISIBLE (-6490 2735);
FORCEPROP 2 LAST CDS_LIB logical_power
J 0
(-6500 2675);
PAINT MONO (-6500 2675);
DISPLAY INVISIBLE (-6500 2675);
FORCEPROP 1 LAST HDL_POWER GND
J 1
(-6475 2600);
DISPLAY 0.872340 (-6475 2600);
PAINT GREEN (-6475 2600);
DISPLAY INVISIBLE (-6475 2600);
FORCEPROP 1 LAST PATH I81
J 0
(-6425 2675);
DISPLAY 0.872340 (-6425 2675);
PAINT AQUA (-6425 2675);
DISPLAY INVISIBLE (-6425 2675);
FORCEADD Q_RES..2
(-7100 100);
FORCEPROP 1 LAST PART_NUMBER CS31002FB08
J 0
(-7060 -75);
DISPLAY 0.510638 (-7060 -75);
DISPLAY INVISIBLE (-7060 -75);
FORCEPROP 1 LAST PACK_TYPE 0402LF
J 0
(-7060 -25);
DISPLAY 0.510638 (-7060 -25);
FORCEPROP 1 LAST WATTAGE 1/16W
J 0
(-7060 75);
DISPLAY 0.510638 (-7060 75);
FORCEPROP 1 LAST TOLERANCE 1%
J 0
(-7055 125);
DISPLAY 0.510638 (-7055 125);
FORCEPROP 1 LAST MATERIAL CHIP
J 0
(-7060 25);
DISPLAY 0.510638 (-7060 25);
FORCEPROP 1 LAST VALUE 10K
J 0
(-7055 175);
DISPLAY 0.510638 (-7055 175);
FORCEPROP 1 LAST $LOCATION R933
J 0
(-7055 225);
DISPLAY 0.978723 (-7055 225);
FORCEPROP 1 LASTPIN (-7100 200) $PN 1
J 0
(-7095 162);
DISPLAY 0.787234 (-7095 162);
FORCEPROP 1 LASTPIN (-7100 0) $PN 2
J 0
(-7095 10);
DISPLAY 0.787234 (-7095 10);
FORCEPROP 2 LAST CDS_LIB pure_quanta
J 0
(-7100 100);
PAINT MONO (-7100 100);
DISPLAY INVISIBLE (-7100 100);
FORCEPROP 1 LAST PATH I82
J 0
(-7050 275);
DISPLAY 0.978723 (-7050 275);
PAINT WHITE (-7050 275);
DISPLAY INVISIBLE (-7050 275);
FORCEPROP 2 LAST CDS_LOCATION R933
J 0
(-7050 325);
DISPLAY 1.021277 (-7050 325);
DISPLAY INVISIBLE (-7050 325);
FORCEPROP 2 LAST $SEC 1
J 0
(-7050 325);
DISPLAY 0.680851 (-7050 325);
PAINT MONO (-7050 325);
DISPLAY INVISIBLE (-7050 325);
FORCEPROP 2 LAST CDS_SEC 1
J 0
(-7050 325);
DISPLAY 1.021277 (-7050 325);
DISPLAY INVISIBLE (-7050 325);
FORCEADD Q_RES..2
(-6500 100);
FORCEPROP 1 LAST PART_NUMBER CS31002FB08
J 0
(-6460 -75);
DISPLAY 0.510638 (-6460 -75);
DISPLAY INVISIBLE (-6460 -75);
FORCEPROP 1 LAST VALUE 10K
J 0
(-6455 175);
DISPLAY 0.510638 (-6455 175);
FORCEPROP 1 LAST WATTAGE 1/16W
J 0
(-6460 75);
DISPLAY 0.510638 (-6460 75);
FORCEPROP 1 LAST PACK_TYPE 0402LF
J 0
(-6460 -25);
DISPLAY 0.510638 (-6460 -25);
FORCEPROP 1 LAST TOLERANCE 1%
J 0
(-6455 125);
DISPLAY 0.510638 (-6455 125);
FORCEPROP 1 LAST MATERIAL CHIP
J 0
(-6460 25);
DISPLAY 0.510638 (-6460 25);
FORCEPROP 1 LAST $LOCATION R939
J 0
(-6455 225);
DISPLAY 0.978723 (-6455 225);
FORCEPROP 1 LASTPIN (-6500 200) $PN 1
J 0
(-6495 162);
DISPLAY 0.787234 (-6495 162);
FORCEPROP 1 LASTPIN (-6500 0) $PN 2
J 0
(-6495 10);
DISPLAY 0.787234 (-6495 10);
FORCEPROP 2 LAST CDS_LIB pure_quanta
J 0
(-6500 100);
PAINT MONO (-6500 100);
DISPLAY INVISIBLE (-6500 100);
FORCEPROP 1 LAST PATH I83
J 0
(-6450 275);
DISPLAY 0.978723 (-6450 275);
PAINT WHITE (-6450 275);
DISPLAY INVISIBLE (-6450 275);
FORCEPROP 2 LAST CDS_LOCATION R939
J 0
(-6450 325);
DISPLAY 1.021277 (-6450 325);
DISPLAY INVISIBLE (-6450 325);
FORCEPROP 2 LAST $SEC 1
J 0
(-6450 325);
DISPLAY 0.680851 (-6450 325);
PAINT MONO (-6450 325);
DISPLAY INVISIBLE (-6450 325);
FORCEPROP 2 LAST CDS_SEC 1
J 0
(-6450 325);
DISPLAY 1.021277 (-6450 325);
DISPLAY INVISIBLE (-6450 325);
FORCEADD UNIVERSAL_GND..1
(-6500 -225);
FORCEPROP 3 LASTPIN (-6500 -175) SIG_NAME GND\g
J 0
(-6490 -165);
DISPLAY 0.659574 (-6490 -165);
PAINT MONO (-6490 -165);
DISPLAY INVISIBLE (-6490 -165);
FORCEPROP 2 LAST CDS_LIB logical_power
J 0
(-6500 -225);
PAINT MONO (-6500 -225);
DISPLAY INVISIBLE (-6500 -225);
FORCEPROP 1 LAST HDL_POWER GND
J 1
(-6475 -300);
DISPLAY 0.872340 (-6475 -300);
PAINT GREEN (-6475 -300);
DISPLAY INVISIBLE (-6475 -300);
FORCEPROP 1 LAST PATH I84
J 0
(-6425 -225);
DISPLAY 0.872340 (-6425 -225);
PAINT AQUA (-6425 -225);
DISPLAY INVISIBLE (-6425 -225);
FORCEADD Q_RES..2
(-6700 100);
FORCEPROP 1 LAST PART_NUMBER CS31002FB08
J 0
(-6660 -75);
DISPLAY 0.510638 (-6660 -75);
DISPLAY INVISIBLE (-6660 -75);
FORCEPROP 1 LAST VALUE 10K
J 0
(-6655 175);
DISPLAY 0.510638 (-6655 175);
FORCEPROP 1 LAST WATTAGE 1/16W
J 0
(-6660 75);
DISPLAY 0.510638 (-6660 75);
FORCEPROP 1 LAST MATERIAL CHIP
J 0
(-6660 25);
DISPLAY 0.510638 (-6660 25);
FORCEPROP 1 LAST TOLERANCE 1%
J 0
(-6655 125);
DISPLAY 0.510638 (-6655 125);
FORCEPROP 1 LAST PACK_TYPE 0402LF
J 0
(-6660 -25);
DISPLAY 0.510638 (-6660 -25);
FORCEPROP 1 LAST $LOCATION R937
J 0
(-6655 225);
DISPLAY 0.978723 (-6655 225);
FORCEPROP 1 LASTPIN (-6700 200) $PN 1
J 0
(-6695 162);
DISPLAY 0.787234 (-6695 162);
FORCEPROP 1 LASTPIN (-6700 0) $PN 2
J 0
(-6695 10);
DISPLAY 0.787234 (-6695 10);
FORCEPROP 2 LAST CDS_LIB pure_quanta
J 0
(-6700 100);
PAINT MONO (-6700 100);
DISPLAY INVISIBLE (-6700 100);
FORCEPROP 1 LAST PATH I85
J 0
(-6650 275);
DISPLAY 0.978723 (-6650 275);
PAINT WHITE (-6650 275);
DISPLAY INVISIBLE (-6650 275);
FORCEPROP 2 LAST CDS_LOCATION R937
J 0
(-6650 325);
DISPLAY 1.021277 (-6650 325);
DISPLAY INVISIBLE (-6650 325);
FORCEPROP 2 LAST $SEC 1
J 0
(-6650 325);
DISPLAY 0.680851 (-6650 325);
PAINT MONO (-6650 325);
DISPLAY INVISIBLE (-6650 325);
FORCEPROP 2 LAST CDS_SEC 1
J 0
(-6650 325);
DISPLAY 1.021277 (-6650 325);
DISPLAY INVISIBLE (-6650 325);
FORCEADD Q_RES..2
(-6900 100);
FORCEPROP 1 LAST PART_NUMBER CS31002FB08
J 0
(-6860 -75);
DISPLAY 0.510638 (-6860 -75);
DISPLAY INVISIBLE (-6860 -75);
FORCEPROP 1 LAST VALUE 10K
J 0
(-6855 175);
DISPLAY 0.510638 (-6855 175);
FORCEPROP 1 LAST MATERIAL CHIP
J 0
(-6860 25);
DISPLAY 0.510638 (-6860 25);
FORCEPROP 1 LAST TOLERANCE 1%
J 0
(-6855 125);
DISPLAY 0.510638 (-6855 125);
FORCEPROP 1 LAST WATTAGE 1/16W
J 0
(-6860 75);
DISPLAY 0.510638 (-6860 75);
FORCEPROP 1 LAST PACK_TYPE 0402LF
J 0
(-6860 -25);
DISPLAY 0.510638 (-6860 -25);
FORCEPROP 1 LAST $LOCATION R935
J 0
(-6855 225);
DISPLAY 0.978723 (-6855 225);
FORCEPROP 1 LASTPIN (-6900 200) $PN 1
J 0
(-6895 162);
DISPLAY 0.787234 (-6895 162);
FORCEPROP 1 LASTPIN (-6900 0) $PN 2
J 0
(-6895 10);
DISPLAY 0.787234 (-6895 10);
FORCEPROP 2 LAST CDS_LIB pure_quanta
J 0
(-6900 100);
PAINT MONO (-6900 100);
DISPLAY INVISIBLE (-6900 100);
FORCEPROP 1 LAST PATH I86
J 0
(-6850 275);
DISPLAY 0.978723 (-6850 275);
PAINT WHITE (-6850 275);
DISPLAY INVISIBLE (-6850 275);
FORCEPROP 2 LAST CDS_LOCATION R935
J 0
(-6850 325);
DISPLAY 1.021277 (-6850 325);
DISPLAY INVISIBLE (-6850 325);
FORCEPROP 2 LAST $SEC 1
J 0
(-6850 325);
DISPLAY 0.680851 (-6850 325);
PAINT MONO (-6850 325);
DISPLAY INVISIBLE (-6850 325);
FORCEPROP 2 LAST CDS_SEC 1
J 0
(-6850 325);
DISPLAY 1.021277 (-6850 325);
DISPLAY INVISIBLE (-6850 325);
FORCEADD Q_RES..1
(-5325 3275);
FORCEPROP 1 LAST PART_NUMBER CS00002JB13
J 0
(-5450 3125);
DISPLAY 0.510638 (-5450 3125);
DISPLAY INVISIBLE (-5450 3125);
FORCEPROP 1 LAST VALUE 0
J 2
(-5175 3275);
DISPLAY 0.638298 (-5175 3275);
FORCEPROP 1 LAST TOLERANCE 5%
J 0
(-5150 3275);
DISPLAY 0.638298 (-5150 3275);
FORCEPROP 1 LAST $LOCATION R854
J 0
(-5525 3275);
DISPLAY 0.638298 (-5525 3275);
FORCEPROP 1 LASTPIN (-5425 3275) $PN 1
J 0
(-5413 3287);
DISPLAY 0.787234 (-5413 3287);
FORCEPROP 1 LASTPIN (-5225 3275) $PN 2
J 0
(-5263 3287);
DISPLAY 0.787234 (-5263 3287);
FORCEPROP 1 LAST WATTAGE 1/16W
J 2
(-5350 3125);
DISPLAY 0.978723 (-5350 3125);
DISPLAY INVISIBLE (-5350 3125);
FORCEPROP 1 LAST MATERIAL CHIP
J 0
(-5325 3125);
DISPLAY 0.978723 (-5325 3125);
DISPLAY INVISIBLE (-5325 3125);
FORCEPROP 2 LAST CDS_LIB pure_quanta
J 0
(-5325 3275);
PAINT MONO (-5325 3275);
DISPLAY INVISIBLE (-5325 3275);
FORCEPROP 1 LAST PACK_TYPE 0402LF
J 0
(-5075 3275);
DISPLAY 0.638298 (-5075 3275);
DISPLAY INVISIBLE (-5075 3275);
FORCEPROP 1 LAST PATH I9
J 0
(-5375 3425);
DISPLAY 0.978723 (-5375 3425);
PAINT WHITE (-5375 3425);
DISPLAY INVISIBLE (-5375 3425);
FORCEPROP 1 LAST $LOCATION R854
J 0
(-5375 3475);
DISPLAY 1.021277 (-5375 3475);
DISPLAY INVISIBLE (-5375 3475);
FORCEPROP 2 LAST CDS_LOCATION R854
J 0
(-5375 3475);
DISPLAY 1.021277 (-5375 3475);
DISPLAY INVISIBLE (-5375 3475);
FORCEPROP 2 LAST $SEC 1
J 0
(-5375 3475);
DISPLAY 0.680851 (-5375 3475);
PAINT MONO (-5375 3475);
DISPLAY INVISIBLE (-5375 3475);
FORCEPROP 2 LAST CDS_SEC 1
J 0
(-5375 3475);
DISPLAY 1.021277 (-5375 3475);
DISPLAY INVISIBLE (-5375 3475);
FORCEADD QUANTA_TITLE_BLOCK_C..1
(875 -1350);
FORCEPROP 0 LAST CDS_CON_LAST_MODIFIED Fri Aug 25 14:01:48 2023
J 0
(-1010 -1335);
PAINT MONO (-1010 -1335);
DISPLAY INVISIBLE (-1010 -1335);
FORCEPROP 2 LAST CUSTOM_TXT_CDS <XR_PAGE_TITLE>
J 0
(-7015 3900);
DISPLAY 0.638298 (-7015 3900);
PAINT PINK (-7015 3900);
DISPLAY INVISIBLE (-7015 3900);
FORCEPROP 2 LAST CUSTOM_TXT_CDS <Q_NUMBER>
J 0
(-528 -1247);
DISPLAY 1.212766 (-528 -1247);
FORCEPROP 2 LAST CUSTOM_TXT_CDS <CON_LAST_MODIFIED>
J 0
(-1010 -1335);
DISPLAY 0.978723 (-1010 -1335);
FORCEPROP 2 LAST CUSTOM_TXT_CDS <NAME_1>
J 0
(-2300 -1175);
FORCEPROP 2 LAST CUSTOM_TXT_CDS <CON_PAGE_NUM> OF <CON_TOTAL_PAGES>
J 0
(429 -1332);
DISPLAY 0.978723 (429 -1332);
FORCEPROP 2 LAST CUSTOM_TXT_CDS <Q_REV>
J 0
(691 -1247);
DISPLAY 1.212766 (691 -1247);
FORCEPROP 2 LAST CUSTOM_TXT_CDS <Q_PROJ>
J 0
(-1507 -1248);
DISPLAY 1.212766 (-1507 -1248);
FORCEPROP 2 LAST CUSTOM_TXT_CDS <NAME_2>
J 0
(-2300 -1300);
FORCEPROP 1 LAST Q_TITLE SPR CPU0 & 1 - DDR RESET CPU TO PLD
J 0
(-8391 -1324);
DISPLAY 2.446809 (-8391 -1324);
PAINT GREEN (-8391 -1324);
FORCEPROP 1 LAST Q_DEPT 
J 1
(-2888 -1301);
DISPLAY 1.957447 (-2888 -1301);
PAINT GREEN (-2888 -1301);
FORCEPROP 2 LAST CDS_XR_PAGE_TITLE CR-128 : @S9S_MB_2U_LIB.S9S_MB_2U(SCH_1):PAGE128
J 0
(-7015 3900);
DISPLAY 0.638298 (-7015 3900);
PAINT PINK (-7015 3900);
DISPLAY INVISIBLE (-7015 3900);
FORCEPROP 1 LAST COMMENT_BODY TRUE
J 0
(887 -1363);
DISPLAY 0.978723 (887 -1363);
PAINT GREEN (887 -1363);
DISPLAY INVISIBLE (887 -1363);
FORCEPROP 2 LAST PAGE_BORDER TRUE
J 0
(-7015 3900);
DISPLAY 0.638298 (-7015 3900);
PAINT PINK (-7015 3900);
DISPLAY INVISIBLE (-7015 3900);
FORCEPROP 1 LAST CDS_LMAN_SYM_OUTLINE -9475,6775,100,-125
J 0
(875 -1350);
DISPLAY 0.468085 (875 -1350);
PAINT GREEN (875 -1350);
DISPLAY INVISIBLE (875 -1350);
FORCEPROP 2 LAST CDS_LIB pure_quanta
J 0
(875 -1350);
PAINT MONO (875 -1350);
DISPLAY INVISIBLE (875 -1350);
WIRE 16 -1 (-6500 -175)(-6500 -125);
WIRE 16 -1 (-6500 2725)(-6500 2775);
WIRE 16 -1 (-5225 375)(-900 375);
FORCEPROP 0 LAST CDS_PHYS_NET_NAME RST_CPU0_DRAM_GH_PLD_N
J 0
(-1575 411);
PAINT MONO (-1575 411);
DISPLAY INVISIBLE (-1575 411);
FORCEPROP 2 LAST SIG_NAME RST_CPU1_DRAM_GH_PLD_N
J 0
(-1575 385);
DISPLAY 0.553191 (-1575 385);
PAINT WHITE (-1575 385);
WIRE 16 -1 (-5225 475)(-900 475);
FORCEPROP 0 LAST CDS_PHYS_NET_NAME RST_CPU0_DRAM_CD_PLD_N
J 0
(-1575 511);
PAINT MONO (-1575 511);
DISPLAY INVISIBLE (-1575 511);
FORCEPROP 2 LAST SIG_NAME RST_CPU1_DRAM_CD_PLD_N
J 0
(-1575 485);
DISPLAY 0.553191 (-1575 485);
PAINT WHITE (-1575 485);
WIRE 16 -1 (-7100 0)(-7100 -125);
WIRE 16 -1 (-7100 -125)(-6900 -125);
WIRE 16 -1 (-6900 0)(-6900 -125);
WIRE 16 -1 (-6900 -125)(-6700 -125);
WIRE 16 -1 (-6700 0)(-6700 -125);
WIRE 16 -1 (-6700 -125)(-6500 -125);
WIRE 16 -1 (-6500 -125)(-6500 0);
WIRE 16 -1 (-6900 475)(-6900 200);
WIRE 16 -1 (-6900 475)(-5425 475);
FORCEPROP 0 LAST CDS_PHYS_NET_NAME RST_CPU0_DRAM_CD_N
J 0
(-5700 225);
PAINT MONO (-5700 225);
DISPLAY INVISIBLE (-5700 225);
FORCEPROP 2 LAST SIG_NAME RST_CPU1_DRAM_CD_N
J 0
(-6335 485);
DISPLAY 0.553191 (-6335 485);
PAINT WHITE (-6335 485);
WIRE 16 -1 (-7250 475)(-6900 475);
WIRE 16 -1 (-6700 200)(-6700 425);
WIRE 16 -1 (-6700 425)(-5425 425);
FORCEPROP 2 LAST SIG_NAME RST_CPU1_DRAM_EF_N
J 0
(-6335 435);
DISPLAY 0.553191 (-6335 435);
PAINT WHITE (-6335 435);
WIRE 16 -1 (-7250 425)(-6700 425);
FORCEPROP 0 LAST CDS_PHYS_NET_NAME RST_CPU0_DRAM_EF_N
J 0
(-7035 461);
PAINT MONO (-7035 461);
DISPLAY INVISIBLE (-7035 461);
WIRE 16 -1 (-6500 200)(-6500 375);
WIRE 16 -1 (-6500 375)(-5425 375);
FORCEPROP 2 LAST SIG_NAME RST_CPU1_DRAM_GH_N
J 0
(-6335 385);
DISPLAY 0.553191 (-6335 385);
PAINT WHITE (-6335 385);
WIRE 16 -1 (-7250 375)(-6500 375);
FORCEPROP 0 LAST CDS_PHYS_NET_NAME RST_CPU0_DRAM_GH_N
J 0
(-7035 411);
PAINT MONO (-7035 411);
DISPLAY INVISIBLE (-7035 411);
WIRE 16 -1 (-7100 200)(-7100 525);
WIRE 16 -1 (-7100 525)(-5425 525);
FORCEPROP 2 LAST SIG_NAME RST_CPU1_DRAM_AB_N
J 0
(-6335 535);
DISPLAY 0.553191 (-6335 535);
PAINT WHITE (-6335 535);
WIRE 16 -1 (-7250 525)(-7100 525);
WIRE 16 -1 (-7100 2900)(-7100 2775);
WIRE 16 -1 (-7100 2775)(-6900 2775);
WIRE 16 -1 (-6900 2900)(-6900 2775);
WIRE 16 -1 (-6900 2775)(-6700 2775);
WIRE 16 -1 (-6700 2900)(-6700 2775);
WIRE 16 -1 (-6700 2775)(-6500 2775);
WIRE 16 -1 (-6500 2775)(-6500 2900);
WIRE 16 -1 (-7100 3100)(-7100 3425);
WIRE 16 -1 (-5425 3425)(-7100 3425);
FORCEPROP 2 LAST SIG_NAME RST_CPU0_DRAM_AB_N
J 0
(-6335 3435);
DISPLAY 0.553191 (-6335 3435);
PAINT WHITE (-6335 3435);
WIRE 16 -1 (-7250 3425)(-7100 3425);
WIRE 16 -1 (-6900 3375)(-6900 3100);
WIRE 16 -1 (-5425 3375)(-6900 3375);
FORCEPROP 0 LAST CDS_PHYS_NET_NAME H_CPU1_MEMHOT_OUT_LVC1_R_N
J 0
(-5700 3125);
PAINT MONO (-5700 3125);
DISPLAY INVISIBLE (-5700 3125);
FORCEPROP 2 LAST SIG_NAME RST_CPU0_DRAM_CD_N
J 0
(-6335 3385);
DISPLAY 0.553191 (-6335 3385);
PAINT WHITE (-6335 3385);
WIRE 16 -1 (-7250 3375)(-6900 3375);
WIRE 16 -1 (-6700 3100)(-6700 3325);
WIRE 16 -1 (-5425 3325)(-6700 3325);
FORCEPROP 2 LAST SIG_NAME RST_CPU0_DRAM_EF_N
J 0
(-6335 3335);
DISPLAY 0.553191 (-6335 3335);
PAINT WHITE (-6335 3335);
WIRE 16 -1 (-7250 3325)(-6700 3325);
FORCEPROP 0 LAST CDS_PHYS_NET_NAME RST_CPU0_DRAM_AB_N
J 0
(-7035 3361);
PAINT MONO (-7035 3361);
DISPLAY INVISIBLE (-7035 3361);
WIRE 16 -1 (-6500 3100)(-6500 3275);
WIRE 16 -1 (-5425 3275)(-6500 3275);
FORCEPROP 2 LAST SIG_NAME RST_CPU0_DRAM_GH_N
J 0
(-6335 3285);
DISPLAY 0.553191 (-6335 3285);
PAINT WHITE (-6335 3285);
WIRE 16 -1 (-7250 3275)(-6500 3275);
FORCEPROP 0 LAST CDS_PHYS_NET_NAME RST_CPU0_DRAM_AB_N
J 0
(-7035 3311);
PAINT MONO (-7035 3311);
DISPLAY INVISIBLE (-7035 3311);
WIRE 16 -1 (-5225 3375)(-900 3375);
FORCEPROP 0 LAST CDS_PHYS_NET_NAME RST_CPU0_DRAM_AB_PLD_N
J 0
(-1575 3411);
PAINT MONO (-1575 3411);
DISPLAY INVISIBLE (-1575 3411);
FORCEPROP 2 LAST SIG_NAME RST_CPU0_DRAM_CD_PLD_N
J 0
(-1575 3385);
DISPLAY 0.553191 (-1575 3385);
PAINT WHITE (-1575 3385);
WIRE 16 -1 (-5225 3325)(-900 3325);
FORCEPROP 0 LAST CDS_PHYS_NET_NAME RST_CPU0_DRAM_AB_PLD_N
J 0
(-1575 3361);
PAINT MONO (-1575 3361);
DISPLAY INVISIBLE (-1575 3361);
FORCEPROP 2 LAST SIG_NAME RST_CPU0_DRAM_EF_PLD_N
J 0
(-1575 3335);
DISPLAY 0.553191 (-1575 3335);
PAINT WHITE (-1575 3335);
WIRE 16 -1 (-5225 3275)(-900 3275);
FORCEPROP 0 LAST CDS_PHYS_NET_NAME RST_CPU0_DRAM_AB_PLD_N
J 0
(-1575 3311);
PAINT MONO (-1575 3311);
DISPLAY INVISIBLE (-1575 3311);
FORCEPROP 2 LAST SIG_NAME RST_CPU0_DRAM_GH_PLD_N
J 0
(-1575 3285);
DISPLAY 0.553191 (-1575 3285);
PAINT WHITE (-1575 3285);
WIRE 16 -1 (-5225 525)(-900 525);
FORCEPROP 2 LAST SIG_NAME RST_CPU1_DRAM_AB_PLD_N
J 0
(-1575 535);
DISPLAY 0.553191 (-1575 535);
PAINT WHITE (-1575 535);
WIRE 16 -1 (-5225 425)(-900 425);
FORCEPROP 0 LAST CDS_PHYS_NET_NAME RST_CPU0_DRAM_EF_PLD_N
J 0
(-1575 461);
PAINT MONO (-1575 461);
DISPLAY INVISIBLE (-1575 461);
FORCEPROP 2 LAST SIG_NAME RST_CPU1_DRAM_EF_PLD_N
J 0
(-1575 435);
DISPLAY 0.553191 (-1575 435);
PAINT WHITE (-1575 435);
WIRE 16 -1 (-5225 3425)(-900 3425);
FORCEPROP 2 LAST SIG_NAME RST_CPU0_DRAM_AB_PLD_N
J 0
(-1575 3435);
DISPLAY 0.553191 (-1575 3435);
PAINT WHITE (-1575 3435);
DOT 1 (-7100 525);
DOT 1 (-6500 2775);
DOT 1 (-6700 2775);
DOT 1 (-6900 -125);
DOT 1 (-6700 -125);
DOT 1 (-6500 -125);
DOT 1 (-6500 375);
DOT 1 (-6700 425);
DOT 1 (-6900 475);
DOT 1 (-6700 3325);
DOT 1 (-6900 3375);
DOT 1 (-7100 3425);
DOT 1 (-6500 3275);
DOT 1 (-6900 2775);
QUIT
